# S9S_MB_2U (Grand Teton) — schematic netlist excerpt (pin names and nets, part order shuffled) for the footprints in the layout excerpt that follows; sources: Cadence DE-HDL packaged netlist, KiCad conversion of 03242023_DA0F0TMBIJ0_F0T_Motherboard_J_brd_V01_OCP.brd

PR4226  Q_RES  499 1% CHIP  pkg 0402LF  page 275 : A = PVCCINFAON_CPU0 ; B = GND
R506  Q_RES  0 5% CHIP  pkg 0402LF  page 240 : A = IRQ_SMI_ACTIVE_BMC_N ; B = IRQ0_A57

(kicad_pcb
	(version 20260206)
	(generator "pcbnew")
	(generator_version "10.0")
	(general
		(thickness 1.6)
		(legacy_teardrops no)
	)
	(paper "A4")
	(title_block
		(title "03242023_DA0F0TMBIJ0_F0T_Motherboard_J_brd_V01_OCP.brd")
		(comment 1 "Grand Teton / footprints 5043-5044 of 6105")
	)
	(layers
		(0 "F.Cu" signal "TOP")
		(4 "In1.Cu" signal "GND")
		(6 "In2.Cu" signal "IN1")
		(8 "In3.Cu" signal "GND1")
		(10 "In4.Cu" signal "IN2")
		(12 "In5.Cu" signal "GND2")
		(14 "In6.Cu" signal "IN3")
		(16 "In7.Cu" signal "GND3")
		(18 "In8.Cu" signal "VCC")
		(20 "In9.Cu" signal "VCC1")
		(22 "In10.Cu" signal "GND4")
		(24 "In11.Cu" signal "IN4")
		(26 "In12.Cu" signal "GND5")
		(28 "In13.Cu" signal "IN5")
		(30 "In14.Cu" signal "GND6")
		(32 "In15.Cu" signal "IN6")
		(34 "In16.Cu" signal "GND7")
		(2 "B.Cu" signal "BOTTOM")
		(9 "F.Adhes" user "F.Adhesive")
		(11 "B.Adhes" user "B.Adhesive")
		(13 "F.Paste" user "Package Geometry/Pastemask Top")
		(15 "B.Paste" user "Package Geometry/Pastemask Bottom")
		(5 "F.SilkS" user "Ref Des/Silkscreen Top")
		(7 "B.SilkS" user "Ref Des/Silkscreen Bottom")
		(1 "F.Mask" user "Board Geometry/Soldermask Top")
		(3 "B.Mask" user "Board Geometry/Soldermask Bottom")
		(17 "Dwgs.User" user "User.Drawings")
		(19 "Cmts.User" user "User.Comments")
		(21 "Eco1.User" user "User.Eco1")
		(23 "Eco2.User" user "User.Eco2")
		(25 "Edge.Cuts" user "Board Geometry/Outline")
		(27 "Margin" user)
		(31 "F.CrtYd" user "Package Geometry/Place Bound Top")
		(29 "B.CrtYd" user "Package Geometry/Place Bound Bottom")
		(35 "F.Fab" user "Ref Des/Assembly Top")
		(33 "B.Fab" user "Ref Des/Assembly Bottom")
	)
	(footprint ""
		(layer "B.Cu")
		(at 137.08888 -9.362948 -90)
		(property "Reference" "R506"
			(at 0 0 90)
			(layer "B.SilkS")
			(hide yes)
			(effects
				(font
					(size 1.27 1.27)
				)
				(justify mirror)
			)
		)
		(property "Value" ""
			(at 0 0 90)
			(layer "B.Fab")
			(effects
				(font
					(size 1.27 1.27)
				)
				(justify mirror)
			)
		)
		(duplicate_pad_numbers_are_jumpers no)
		(fp_line
			(start -0.7874 0.4064)
			(end 0.7874 0.4064)
			(stroke
				(width 0.1524)
				(type default)
			)
			(layer "B.SilkS")
		)
		(fp_line
			(start 0.7874 0.4064)
			(end 0.7874 -0.4064)
			(stroke
				(width 0.1524)
				(type default)
			)
			(layer "B.SilkS")
		)
		(fp_line
			(start -0.7874 -0.4064)
			(end -0.7874 0.4064)
			(stroke
				(width 0.1524)
				(type default)
			)
			(layer "B.SilkS")
		)
		(fp_line
			(start 0.7874 -0.4064)
			(end -0.7874 -0.4064)
			(stroke
				(width 0.1524)
				(type default)
			)
			(layer "B.SilkS")
		)
		(fp_line
			(start -0.67945 0.3048)
			(end -0.120396 0.3048)
			(stroke
				(width 0.1)
				(type default)
			)
			(layer "B.Fab")
		)
		(fp_line
			(start -0.120396 0.3048)
			(end -0.120396 0.2794)
			(stroke
				(width 0.1)
				(type default)
			)
			(layer "B.Fab")
		)
		(fp_line
			(start 0.12065 0.3048)
			(end 0.67945 0.3048)
			(stroke
				(width 0.1)
				(type default)
			)
			(layer "B.Fab")
		)
		(fp_line
			(start 0.67945 0.3048)
			(end 0.67945 -0.305054)
			(stroke
				(width 0.1)
				(type default)
			)
			(layer "B.Fab")
		)
		(fp_line
			(start -0.120396 0.2794)
			(end 0.12065 0.2794)
			(stroke
				(width 0.1)
				(type default)
			)
			(layer "B.Fab")
		)
		(fp_line
			(start 0.12065 0.2794)
			(end 0.12065 0.3048)
			(stroke
				(width 0.1)
				(type default)
			)
			(layer "B.Fab")
		)
		(fp_line
			(start -0.12065 -0.2794)
			(end -0.12065 -0.3048)
			(stroke
				(width 0.1)
				(type default)
			)
			(layer "B.Fab")
		)
		(fp_line
			(start 0.12065 -0.2794)
			(end -0.12065 -0.2794)
			(stroke
				(width 0.1)
				(type default)
			)
			(layer "B.Fab")
		)
		(fp_line
			(start -0.67945 -0.3048)
			(end -0.67945 0.3048)
			(stroke
				(width 0.1)
				(type default)
			)
			(layer "B.Fab")
		)
		(fp_line
			(start -0.12065 -0.3048)
			(end -0.67945 -0.3048)
			(stroke
				(width 0.1)
				(type default)
			)
			(layer "B.Fab")
		)
		(fp_line
			(start 0.12065 -0.305054)
			(end 0.12065 -0.2794)
			(stroke
				(width 0.1)
				(type default)
			)
			(layer "B.Fab")
		)
		(fp_line
			(start 0.67945 -0.305054)
			(end 0.12065 -0.305054)
			(stroke
				(width 0.1)
				(type default)
			)
			(layer "B.Fab")
		)
		(pad "1" smd circle
			(at 0.40005 0 90)
			(size 0 0)
			(layers "B.Cu" "B.Mask" "B.Paste")
			(net "IRQ_SMI_ACTIVE_BMC_N")
		)
		(pad "2" smd circle
			(at -0.40005 0 90)
			(size 0 0)
			(layers "B.Cu" "B.Mask" "B.Paste")
			(net "IRQ0_A57")
		)
	)
	(footprint ""
		(layer "B.Cu")
		(at 407.90368 -184.165748 180)
		(property "Reference" "PR4226"
			(at 0 0 0)
			(layer "B.SilkS")
			(hide yes)
			(effects
				(font
					(size 1.27 1.27)
				)
				(justify mirror)
			)
		)
		(property "Value" ""
			(at 0 0 0)
			(layer "B.Fab")
			(effects
				(font
					(size 1.27 1.27)
				)
				(justify mirror)
			)
		)
		(duplicate_pad_numbers_are_jumpers no)
		(fp_line
			(start 0.7874 0.4064)
			(end 0.7874 -0.4064)
			(stroke
				(width 0.1524)
				(type default)
			)
			(layer "B.SilkS")
		)
		(fp_line
			(start 0.7874 -0.4064)
			(end -0.7874 -0.4064)
			(stroke
				(width 0.1524)
				(type default)
			)
			(layer "B.SilkS")
		)
		(fp_line
			(start -0.7874 0.4064)
			(end 0.7874 0.4064)
			(stroke
				(width 0.1524)
				(type default)
			)
			(layer "B.SilkS")
		)
		(fp_line
			(start -0.7874 -0.4064)
			(end -0.7874 0.4064)
			(stroke
				(width 0.1524)
				(type default)
			)
			(layer "B.SilkS")
		)
		(fp_line
			(start 0.67945 0.3048)
			(end 0.67945 -0.305054)
			(stroke
				(width 0.1)
				(type default)
			)
			(layer "B.Fab")
		)
		(fp_line
			(start 0.67945 -0.305054)
			(end 0.12065 -0.305054)
			(stroke
				(width 0.1)
				(type default)
			)
			(layer "B.Fab")
		)
		(fp_line
			(start 0.12065 0.3048)
			(end 0.67945 0.3048)
			(stroke
				(width 0.1)
				(type default)
			)
			(layer "B.Fab")
		)
		(fp_line
			(start 0.12065 0.2794)
			(end 0.12065 0.3048)
			(stroke
				(width 0.1)
				(type default)
			)
			(layer "B.Fab")
		)
		(fp_line
			(start 0.12065 -0.2794)
			(end -0.12065 -0.2794)
			(stroke
				(width 0.1)
				(type default)
			)
			(layer "B.Fab")
		)
		(fp_line
			(start 0.12065 -0.305054)
			(end 0.12065 -0.2794)
			(stroke
				(width 0.1)
				(type default)
			)
			(layer "B.Fab")
		)
		(fp_line
			(start -0.120396 0.3048)
			(end -0.120396 0.2794)
			(stroke
				(width 0.1)
				(type default)
			)
			(layer "B.Fab")
		)
		(fp_line
			(start -0.120396 0.2794)
			(end 0.12065 0.2794)
			(stroke
				(width 0.1)
				(type default)
			)
			(layer "B.Fab")
		)
		(fp_line
			(start -0.12065 -0.2794)
			(end -0.12065 -0.3048)
			(stroke
				(width 0.1)
				(type default)
			)
			(layer "B.Fab")
		)
		(fp_line
			(start -0.12065 -0.3048)
			(end -0.67945 -0.3048)
			(stroke
				(width 0.1)
				(type default)
			)
			(layer "B.Fab")
		)
		(fp_line
			(start -0.67945 0.3048)
			(end -0.120396 0.3048)
			(stroke
				(width 0.1)
				(type default)
			)
			(layer "B.Fab")
		)
		(fp_line
			(start -0.67945 -0.3048)
			(end -0.67945 0.3048)
			(stroke
				(width 0.1)
				(type default)
			)
			(layer "B.Fab")
		)
		(pad "1" smd circle
			(at 0.40005 0)
			(size 0 0)
			(layers "B.Cu" "B.Mask" "B.Paste")
			(net "PVCCINFAON_CPU0")
		)
		(pad "2" smd circle
			(at -0.40005 0)
			(size 0 0)
			(layers "B.Cu" "B.Mask" "B.Paste")
			(net "GND")
		)
	)
)
